(kicad_pcb
	(version 20260206)
	(generator "pcbnew")
	(generator_version "10.0")
	(general
		(thickness 1.6)
		(legacy_teardrops no)
	)
	(paper "A4")
	(title_block
		(title "12092022_DA0F0TFB6D0_F0T_FAN_BOARD_MP5048_D_brd_v02_OCP.brd")
		(comment 1 "Grand Teton / footprints 723-726 of 924")
	)
	(layers
		(0 "F.Cu" signal "TOP")
		(4 "In1.Cu" signal "GND")
		(6 "In2.Cu" signal "IN1")
		(8 "In3.Cu" signal "IN2")
		(10 "In4.Cu" signal "GND1")
		(2 "B.Cu" signal "BOTTOM")
		(9 "F.Adhes" user "F.Adhesive")
		(11 "B.Adhes" user "B.Adhesive")
		(13 "F.Paste" user "Package Geometry/Pastemask Top")
		(15 "B.Paste" user "Package Geometry/Pastemask Bottom")
		(5 "F.SilkS" user "Ref Des/Silkscreen Top")
		(7 "B.SilkS" user "Ref Des/Silkscreen Bottom")
		(1 "F.Mask" user "Board Geometry/Soldermask Top")
		(3 "B.Mask" user "Board Geometry/Soldermask Bottom")
		(17 "Dwgs.User" user "User.Drawings")
		(19 "Cmts.User" user "User.Comments")
		(21 "Eco1.User" user "User.Eco1")
		(23 "Eco2.User" user "User.Eco2")
		(25 "Edge.Cuts" user "Board Geometry/Outline")
		(27 "Margin" user)
		(31 "F.CrtYd" user "Package Geometry/Place Bound Top")
		(29 "B.CrtYd" user "Package Geometry/Place Bound Bottom")
		(35 "F.Fab" user "Ref Des/Assembly Top")
		(33 "B.Fab" user "Ref Des/Assembly Bottom")
	)
	(footprint ""
		(layer "F.Cu")
		(at 3.81 -181.61 180)
		(property "Reference" "R2362"
			(at 0 0 180)
			(layer "F.SilkS")
			(hide yes)
			(effects
				(font
					(size 1.27 1.27)
				)
			)
		)
		(property "Value" ""
			(at 0 0 180)
			(layer "F.Fab")
			(effects
				(font
					(size 1.27 1.27)
				)
			)
		)
		(duplicate_pad_numbers_are_jumpers no)
		(fp_line
			(start 0.7874 0.4064)
			(end -0.7874 0.4064)
			(stroke
				(width 0.1524)
				(type default)
			)
			(layer "F.SilkS")
		)
		(fp_line
			(start 0.7874 -0.4064)
			(end 0.7874 0.4064)
			(stroke
				(width 0.1524)
				(type default)
			)
			(layer "F.SilkS")
		)
		(fp_line
			(start -0.7874 0.4064)
			(end -0.7874 -0.4064)
			(stroke
				(width 0.1524)
				(type default)
			)
			(layer "F.SilkS")
		)
		(fp_line
			(start -0.7874 -0.4064)
			(end 0.7874 -0.4064)
			(stroke
				(width 0.1524)
				(type default)
			)
			(layer "F.SilkS")
		)
		(fp_line
			(start 0.67945 0.3048)
			(end 0.120396 0.3048)
			(stroke
				(width 0.1)
				(type default)
			)
			(layer "F.Fab")
		)
		(fp_line
			(start 0.67945 -0.3048)
			(end 0.67945 0.3048)
			(stroke
				(width 0.1)
				(type default)
			)
			(layer "F.Fab")
		)
		(fp_line
			(start 0.12065 -0.2794)
			(end 0.12065 -0.3048)
			(stroke
				(width 0.1)
				(type default)
			)
			(layer "F.Fab")
		)
		(fp_line
			(start 0.12065 -0.3048)
			(end 0.67945 -0.3048)
			(stroke
				(width 0.1)
				(type default)
			)
			(layer "F.Fab")
		)
		(fp_line
			(start 0.120396 0.3048)
			(end 0.120396 0.2794)
			(stroke
				(width 0.1)
				(type default)
			)
			(layer "F.Fab")
		)
		(fp_line
			(start 0.120396 0.2794)
			(end -0.12065 0.2794)
			(stroke
				(width 0.1)
				(type default)
			)
			(layer "F.Fab")
		)
		(fp_line
			(start -0.12065 0.3048)
			(end -0.67945 0.3048)
			(stroke
				(width 0.1)
				(type default)
			)
			(layer "F.Fab")
		)
		(fp_line
			(start -0.12065 0.2794)
			(end -0.12065 0.3048)
			(stroke
				(width 0.1)
				(type default)
			)
			(layer "F.Fab")
		)
		(fp_line
			(start -0.12065 -0.2794)
			(end 0.12065 -0.2794)
			(stroke
				(width 0.1)
				(type default)
			)
			(layer "F.Fab")
		)
		(fp_line
			(start -0.12065 -0.305054)
			(end -0.12065 -0.2794)
			(stroke
				(width 0.1)
				(type default)
			)
			(layer "F.Fab")
		)
		(fp_line
			(start -0.67945 0.3048)
			(end -0.67945 -0.305054)
			(stroke
				(width 0.1)
				(type default)
			)
			(layer "F.Fab")
		)
		(fp_line
			(start -0.67945 -0.305054)
			(end -0.12065 -0.305054)
			(stroke
				(width 0.1)
				(type default)
			)
			(layer "F.Fab")
		)
		(pad "1" smd circle
			(at -0.40005 0 180)
			(size 0 0)
			(layers "F.Cu" "F.Mask" "F.Paste")
			(net "PCA9555_MB0_A2")
		)
		(pad "2" smd circle
			(at 0.40005 0 180)
			(size 0 0)
			(layers "F.Cu" "F.Mask" "F.Paste")
			(net "GND")
		)
	)
	(footprint ""
		(layer "F.Cu")
		(at 14.0589 -124.587 180)
		(property "Reference" "R5587"
			(at 0 0 180)
			(layer "F.SilkS")
			(hide yes)
			(effects
				(font
					(size 1.27 1.27)
				)
			)
		)
		(property "Value" ""
			(at 0 0 180)
			(layer "F.Fab")
			(effects
				(font
					(size 1.27 1.27)
				)
			)
		)
		(duplicate_pad_numbers_are_jumpers no)
		(fp_line
			(start 0.7874 0.4064)
			(end -0.7874 0.4064)
			(stroke
				(width 0.1524)
				(type default)
			)
			(layer "F.SilkS")
		)
		(fp_line
			(start 0.7874 -0.4064)
			(end 0.7874 0.4064)
			(stroke
				(width 0.1524)
				(type default)
			)
			(layer "F.SilkS")
		)
		(fp_line
			(start -0.7874 0.4064)
			(end -0.7874 -0.4064)
			(stroke
				(width 0.1524)
				(type default)
			)
			(layer "F.SilkS")
		)
		(fp_line
			(start -0.7874 -0.4064)
			(end 0.7874 -0.4064)
			(stroke
				(width 0.1524)
				(type default)
			)
			(layer "F.SilkS")
		)
		(fp_line
			(start 0.67945 0.3048)
			(end 0.120396 0.3048)
			(stroke
				(width 0.1)
				(type default)
			)
			(layer "F.Fab")
		)
		(fp_line
			(start 0.67945 -0.3048)
			(end 0.67945 0.3048)
			(stroke
				(width 0.1)
				(type default)
			)
			(layer "F.Fab")
		)
		(fp_line
			(start 0.12065 -0.2794)
			(end 0.12065 -0.3048)
			(stroke
				(width 0.1)
				(type default)
			)
			(layer "F.Fab")
		)
		(fp_line
			(start 0.12065 -0.3048)
			(end 0.67945 -0.3048)
			(stroke
				(width 0.1)
				(type default)
			)
			(layer "F.Fab")
		)
		(fp_line
			(start 0.120396 0.3048)
			(end 0.120396 0.2794)
			(stroke
				(width 0.1)
				(type default)
			)
			(layer "F.Fab")
		)
		(fp_line
			(start 0.120396 0.2794)
			(end -0.12065 0.2794)
			(stroke
				(width 0.1)
				(type default)
			)
			(layer "F.Fab")
		)
		(fp_line
			(start -0.12065 0.3048)
			(end -0.67945 0.3048)
			(stroke
				(width 0.1)
				(type default)
			)
			(layer "F.Fab")
		)
		(fp_line
			(start -0.12065 0.2794)
			(end -0.12065 0.3048)
			(stroke
				(width 0.1)
				(type default)
			)
			(layer "F.Fab")
		)
		(fp_line
			(start -0.12065 -0.2794)
			(end 0.12065 -0.2794)
			(stroke
				(width 0.1)
				(type default)
			)
			(layer "F.Fab")
		)
		(fp_line
			(start -0.12065 -0.305054)
			(end -0.12065 -0.2794)
			(stroke
				(width 0.1)
				(type default)
			)
			(layer "F.Fab")
		)
		(fp_line
			(start -0.67945 0.3048)
			(end -0.67945 -0.305054)
			(stroke
				(width 0.1)
				(type default)
			)
			(layer "F.Fab")
		)
		(fp_line
			(start -0.67945 -0.305054)
			(end -0.12065 -0.305054)
			(stroke
				(width 0.1)
				(type default)
			)
			(layer "F.Fab")
		)
		(pad "1" smd rect
			(at -0.40005 0)
			(size 0.4572 0.508)
			(layers "F.Cu" "F.Mask" "F.Paste")
			(net "FAN_5_TACH_IL")
		)
		(pad "2" smd rect
			(at 0.40005 0)
			(size 0.4572 0.508)
			(layers "F.Cu" "F.Mask" "F.Paste")
			(net "FAN_5_TACH_IL_R2")
		)
	)
	(footprint ""
		(layer "B.Cu")
		(at 9.906 -168.783 180)
		(property "Reference" "C57"
			(at 0 0 0)
			(layer "B.SilkS")
			(hide yes)
			(effects
				(font
					(size 1.27 1.27)
				)
				(justify mirror)
			)
		)
		(property "Value" ""
			(at 0 0 0)
			(layer "B.Fab")
			(effects
				(font
					(size 1.27 1.27)
				)
				(justify mirror)
			)
		)
		(duplicate_pad_numbers_are_jumpers no)
		(fp_line
			(start 0.7874 0.4064)
			(end 0.7874 -0.4064)
			(stroke
				(width 0.1524)
				(type default)
			)
			(layer "B.SilkS")
		)
		(fp_line
			(start 0.7874 -0.4064)
			(end -0.7874 -0.4064)
			(stroke
				(width 0.1524)
				(type default)
			)
			(layer "B.SilkS")
		)
		(fp_line
			(start -0.7874 0.4064)
			(end 0.7874 0.4064)
			(stroke
				(width 0.1524)
				(type default)
			)
			(layer "B.SilkS")
		)
		(fp_line
			(start -0.7874 -0.4064)
			(end -0.7874 0.4064)
			(stroke
				(width 0.1524)
				(type default)
			)
			(layer "B.SilkS")
		)
		(fp_line
			(start 0.67945 0.3048)
			(end 0.67945 -0.305054)
			(stroke
				(width 0.1)
				(type default)
			)
			(layer "B.Fab")
		)
		(fp_line
			(start 0.67945 -0.305054)
			(end 0.12065 -0.305054)
			(stroke
				(width 0.1)
				(type default)
			)
			(layer "B.Fab")
		)
		(fp_line
			(start 0.12065 0.3048)
			(end 0.67945 0.3048)
			(stroke
				(width 0.1)
				(type default)
			)
			(layer "B.Fab")
		)
		(fp_line
			(start 0.12065 0.2794)
			(end 0.12065 0.3048)
			(stroke
				(width 0.1)
				(type default)
			)
			(layer "B.Fab")
		)
		(fp_line
			(start 0.12065 -0.2794)
			(end -0.12065 -0.2794)
			(stroke
				(width 0.1)
				(type default)
			)
			(layer "B.Fab")
		)
		(fp_line
			(start 0.12065 -0.305054)
			(end 0.12065 -0.2794)
			(stroke
				(width 0.1)
				(type default)
			)
			(layer "B.Fab")
		)
		(fp_line
			(start -0.120396 0.3048)
			(end -0.120396 0.2794)
			(stroke
				(width 0.1)
				(type default)
			)
			(layer "B.Fab")
		)
		(fp_line
			(start -0.120396 0.2794)
			(end 0.12065 0.2794)
			(stroke
				(width 0.1)
				(type default)
			)
			(layer "B.Fab")
		)
		(fp_line
			(start -0.12065 -0.2794)
			(end -0.12065 -0.3048)
			(stroke
				(width 0.1)
				(type default)
			)
			(layer "B.Fab")
		)
		(fp_line
			(start -0.12065 -0.3048)
			(end -0.67945 -0.3048)
			(stroke
				(width 0.1)
				(type default)
			)
			(layer "B.Fab")
		)
		(fp_line
			(start -0.67945 0.3048)
			(end -0.120396 0.3048)
			(stroke
				(width 0.1)
				(type default)
			)
			(layer "B.Fab")
		)
		(fp_line
			(start -0.67945 -0.3048)
			(end -0.67945 0.3048)
			(stroke
				(width 0.1)
				(type default)
			)
			(layer "B.Fab")
		)
		(pad "1" smd circle
			(at 0.40005 0)
			(size 0 0)
			(layers "B.Cu" "B.Mask" "B.Paste")
			(net "P3V3_AUX")
		)
		(pad "2" smd circle
			(at -0.40005 0)
			(size 0 0)
			(layers "B.Cu" "B.Mask" "B.Paste")
			(net "GND")
		)
	)
	(footprint ""
		(layer "B.Cu")
		(at 44.704 -313.436 -90)
		(property "Reference" "C2120"
			(at 0 0 90)
			(layer "B.SilkS")
			(hide yes)
			(effects
				(font
					(size 1.27 1.27)
				)
				(justify mirror)
			)
		)
		(property "Value" ""
			(at 0 0 90)
			(layer "B.Fab")
			(effects
				(font
					(size 1.27 1.27)
				)
				(justify mirror)
			)
		)
		(duplicate_pad_numbers_are_jumpers no)
		(fp_line
			(start -1.2954 0.5842)
			(end 1.2954 0.5842)
			(stroke
				(width 0.1524)
				(type default)
			)
			(layer "B.SilkS")
		)
		(fp_line
			(start 1.2954 0.5842)
			(end 1.2954 -0.5842)
			(stroke
				(width 0.1524)
				(type default)
			)
			(layer "B.SilkS")
		)
		(fp_line
			(start -1.2954 -0.5842)
			(end -1.2954 0.5842)
			(stroke
				(width 0.1524)
				(type default)
			)
			(layer "B.SilkS")
		)
		(fp_line
			(start 1.2954 -0.5842)
			(end -1.2954 -0.5842)
			(stroke
				(width 0.1524)
				(type default)
			)
			(layer "B.SilkS")
		)
		(fp_line
			(start -0.8636 0.4572)
			(end 0.8636 0.4572)
			(stroke
				(width 0.1)
				(type default)
			)
			(layer "B.Fab")
		)
		(fp_line
			(start 0.8636 0.4572)
			(end 0.8636 0.4064)
			(stroke
				(width 0.1)
				(type default)
			)
			(layer "B.Fab")
		)
		(fp_line
			(start -1.1938 0.4064)
			(end -0.8636 0.4064)
			(stroke
				(width 0.1)
				(type default)
			)
			(layer "B.Fab")
		)
		(fp_line
			(start -0.8636 0.4064)
			(end -0.8636 0.4572)
			(stroke
				(width 0.1)
				(type default)
			)
			(layer "B.Fab")
		)
		(fp_line
			(start 0.8636 0.4064)
			(end 1.1938 0.4064)
			(stroke
				(width 0.1)
				(type default)
			)
			(layer "B.Fab")
		)
		(fp_line
			(start 1.1938 0.4064)
			(end 1.1938 -0.4064)
			(stroke
				(width 0.1)
				(type default)
			)
			(layer "B.Fab")
		)
		(fp_line
			(start -1.1938 -0.4064)
			(end -1.1938 0.4064)
			(stroke
				(width 0.1)
				(type default)
			)
			(layer "B.Fab")
		)
		(fp_line
			(start -0.8636 -0.4064)
			(end -1.1938 -0.4064)
			(stroke
				(width 0.1)
				(type default)
			)
			(layer "B.Fab")
		)
		(fp_line
			(start 0.8636 -0.4064)
			(end 0.8636 -0.4572)
			(stroke
				(width 0.1)
				(type default)
			)
			(layer "B.Fab")
		)
		(fp_line
			(start 1.1938 -0.4064)
			(end 0.8636 -0.4064)
			(stroke
				(width 0.1)
				(type default)
			)
			(layer "B.Fab")
		)
		(fp_line
			(start -0.8636 -0.4572)
			(end -0.8636 -0.4064)
			(stroke
				(width 0.1)
				(type default)
			)
			(layer "B.Fab")
		)
		(fp_line
			(start 0.8636 -0.4572)
			(end -0.8636 -0.4572)
			(stroke
				(width 0.1)
				(type default)
			)
			(layer "B.Fab")
		)
		(pad "1" smd rect
			(at 0.7366 0 180)
			(size 0.7112 0.8128)
			(layers "B.Cu" "B.Mask" "B.Paste")
			(net "U405_D1")
		)
		(pad "2" smd rect
			(at -0.7366 0 180)
			(size 0.7112 0.8128)
			(layers "B.Cu" "B.Mask" "B.Paste")
			(net "GND")
		)
	)
)
